# BASEBOARD_FAB2 (Tioga Pass) — schematic netlist excerpt (pin names and nets, part order shuffled) for the footprints in the layout excerpt that follows; sources: Cadence DE-HDL packaged netlist, KiCad conversion of Wiwynn_Tioga_Pass_MB.brd

J8E1  SCONN11_H67026001  CONN  pkg SM  page 184
  IO1  = SPI_PCH_TPM_CLK_R
  IO2  = RST_PLTRST_BUF_N
  IO3  = SPI_PCH_TPM_MOSI_R
  IO4  = SPI_PCH_TPM_MISO_R
  IO5  = SPI_PCH_TPM_CS_R_N
  IO6  = SMB_SENSOR_STBY_LVC3_SDA
  IO7  = P3V3_STBY
  IO8  = FM_TPM_PRES_RST_N
  IO9  = IRQ_SPI_TPM_N_R
  IO10  = SMB_SENSOR_STBY_LVC3_SCL
  IO11  = GND
  MP1  = GND
  MP2  = GND

(kicad_pcb
	(version 20260206)
	(generator "pcbnew")
	(generator_version "10.0")
	(general
		(thickness 1.6)
		(legacy_teardrops no)
	)
	(paper "A4")
	(title_block
		(title "Wiwynn_Tioga_Pass_MB.brd")
		(comment 1 "Tioga Pass / footprints 525-525 of 4770")
	)
	(layers
		(0 "F.Cu" signal "TOP")
		(4 "In1.Cu" signal "L2GND")
		(6 "In2.Cu" signal "L3")
		(8 "In3.Cu" signal "L4GND")
		(10 "In4.Cu" signal "L5")
		(12 "In5.Cu" signal "L6GND")
		(14 "In6.Cu" signal "L7VCC")
		(16 "In7.Cu" signal "L8VCC")
		(18 "In8.Cu" signal "L9GND")
		(20 "In9.Cu" signal "L10")
		(22 "In10.Cu" signal "L11GND")
		(24 "In11.Cu" signal "L12")
		(26 "In12.Cu" signal "L13GND")
		(2 "B.Cu" signal "BOTTOM")
		(9 "F.Adhes" user "F.Adhesive")
		(11 "B.Adhes" user "B.Adhesive")
		(13 "F.Paste" user "Package Geometry/Pastemask Top")
		(15 "B.Paste" user "Package Geometry/Pastemask Bottom")
		(5 "F.SilkS" user "Ref Des/Silkscreen Top")
		(7 "B.SilkS" user "Ref Des/Silkscreen Bottom")
		(1 "F.Mask" user "Board Geometry/Soldermask Top")
		(3 "B.Mask" user "Board Geometry/Soldermask Bottom")
		(17 "Dwgs.User" user "User.Drawings")
		(19 "Cmts.User" user "User.Comments")
		(21 "Eco1.User" user "User.Eco1")
		(23 "Eco2.User" user "User.Eco2")
		(25 "Edge.Cuts" user "Board Geometry/Outline")
		(27 "Margin" user)
		(31 "F.CrtYd" user "Package Geometry/Place Bound Top")
		(29 "B.CrtYd" user "Package Geometry/Place Bound Bottom")
		(35 "F.Fab" user "Ref Des/Assembly Top")
		(33 "B.Fab" user "Ref Des/Assembly Bottom")
	)
	(footprint ""
		(layer "F.Cu")
		(at 410.340048 -66.529966)
		(property "Reference" "J8E1"
			(at 0.762 9.42213 180)
			(unlocked yes)
			(layer "F.SilkS")
			(effects
				(font
					(size 0.7874 0.5842)
					(thickness 0.1524)
				)
			)
		)
		(property "Value" ""
			(at 0 0 0)
			(layer "F.Fab")
			(effects
				(font
					(size 1.27 1.27)
				)
			)
		)
		(duplicate_pad_numbers_are_jumpers no)
		(fp_poly
			(pts
				(xy -1.048512 -0.391414) (xy -1.587246 -1.648714) (xy -2.305558 -0.930402)
			)
			(stroke
				(width 0)
				(type default)
			)
			(fill yes)
			(layer "F.SilkS")
		)
		(fp_rect
			(start -0.4572 7.72922)
			(end 4.6736 -2.71018)
			(stroke
				(width 0)
				(type default)
			)
			(fill no)
			(layer "F.CrtYd")
		)
		(fp_line
			(start -0.4572 -2.71018)
			(end -0.4572 7.72922)
			(stroke
				(width 0.1)
				(type default)
			)
			(layer "F.Fab")
		)
		(fp_line
			(start -0.4572 7.72922)
			(end 4.6736 7.72922)
			(stroke
				(width 0.1)
				(type default)
			)
			(layer "F.Fab")
		)
		(fp_line
			(start 4.6736 -2.71018)
			(end -0.4572 -2.71018)
			(stroke
				(width 0.1)
				(type default)
			)
			(layer "F.Fab")
		)
		(fp_line
			(start 4.6736 7.72922)
			(end 4.6736 -2.71018)
			(stroke
				(width 0.1)
				(type default)
			)
			(layer "F.Fab")
		)
		(fp_poly
			(pts
				(xy -1.215644 -0.006858) (xy -2.485644 0.501142) (xy -2.485644 -0.514858)
			)
			(stroke
				(width 0)
				(type default)
			)
			(fill yes)
			(layer "F.Fab")
		)
		(fp_text user "6"
			(at -1.763776 5.710682 0)
			(unlocked yes)
			(layer "F.SilkS")
			(effects
				(font
					(size 0.7874 0.5842)
					(thickness 0.1524)
				)
				(justify left)
			)
		)
		(fp_text user "7"
			(at 5.340604 1.199642 0)
			(unlocked yes)
			(layer "F.SilkS")
			(effects
				(font
					(size 0.7874 0.5842)
					(thickness 0.1524)
				)
				(justify left)
			)
		)
		(fp_text user "11"
			(at 5.407152 6.367018 0)
			(unlocked yes)
			(layer "F.SilkS")
			(effects
				(font
					(size 0.7874 0.5842)
					(thickness 0.1524)
				)
				(justify left)
			)
		)
		(fp_text user "6"
			(at -2.42951 4.930394 0)
			(unlocked yes)
			(layer "F.Fab")
			(effects
				(font
					(size 0.7874 0.5842)
					(thickness 0.1524)
				)
				(justify left)
			)
		)
		(fp_text user "11"
			(at 5.280152 4.716018 0)
			(unlocked yes)
			(layer "F.Fab")
			(effects
				(font
					(size 0.7874 0.5842)
					(thickness 0.1524)
				)
				(justify left)
			)
		)
		(fp_text user "7"
			(at 6.282944 0.5588 0)
			(unlocked yes)
			(layer "F.Fab")
			(effects
				(font
					(size 0.7874 0.5842)
					(thickness 0.1524)
				)
				(justify left)
			)
		)
		(pad "" np_thru_hole circle
			(at 3.20802 -0.52578)
			(size 0.254 0.254)
			(drill 0.762)
			(layers "*.Cu" "*.Mask")
			(clearance 0.5715)
			(thermal_gap 0.5715)
		)
		(pad "" np_thru_hole circle
			(at 3.20802 5.51942)
			(size 0.254 0.254)
			(drill 0.762)
			(layers "*.Cu" "*.Mask")
			(clearance 0.5715)
			(thermal_gap 0.5715)
		)
		(pad "1" smd rect
			(at 0 0)
			(size 1.6256 0.6096)
			(layers "F.Cu" "F.Mask" "F.Paste")
			(net "SPI_PCH_TPM_CLK_R")
		)
		(pad "2" smd rect
			(at 0 0.999998)
			(size 1.6256 0.6096)
			(layers "F.Cu" "F.Mask" "F.Paste")
			(net "RST_PLTRST_BUF_N")
		)
		(pad "3" smd rect
			(at 0 1.999996)
			(size 1.6256 0.6096)
			(layers "F.Cu" "F.Mask" "F.Paste")
			(net "SPI_PCH_TPM_MOSI_R")
		)
		(pad "4" smd rect
			(at 0 2.999994)
			(size 1.6256 0.6096)
			(layers "F.Cu" "F.Mask" "F.Paste")
			(net "SPI_PCH_TPM_MISO_R")
		)
		(pad "5" smd rect
			(at 0 3.999992)
			(size 1.6256 0.6096)
			(layers "F.Cu" "F.Mask" "F.Paste")
			(net "SPI_PCH_TPM_CS_R_N")
		)
		(pad "6" smd rect
			(at 0 4.99999)
			(size 1.6256 0.6096)
			(layers "F.Cu" "F.Mask" "F.Paste")
			(net "SMB_SENSOR_STBY_LVC3_SDA")
		)
		(pad "7" smd rect
			(at 4.2164 0.499872)
			(size 1.6256 0.6096)
			(layers "F.Cu" "F.Mask" "F.Paste")
			(net "P3V3_STBY")
		)
		(pad "8" smd rect
			(at 4.2164 1.49987)
			(size 1.6256 0.6096)
			(layers "F.Cu" "F.Mask" "F.Paste")
			(net "FM_TPM_PRES_RST_N")
		)
		(pad "9" smd rect
			(at 4.2164 2.499868)
			(size 1.6256 0.6096)
			(layers "F.Cu" "F.Mask" "F.Paste")
			(net "IRQ_SPI_TPM_N_R")
		)
		(pad "10" smd rect
			(at 4.2164 3.499866)
			(size 1.6256 0.6096)
			(layers "F.Cu" "F.Mask" "F.Paste")
			(net "SMB_SENSOR_STBY_LVC3_SCL")
		)
		(pad "11" smd rect
			(at 4.2164 4.499864)
			(size 1.6256 0.6096)
			(layers "F.Cu" "F.Mask" "F.Paste")
			(net "GND")
		)
		(pad "MP1" smd custom
			(at 2.1082 -1.71958)
			(size 0.34925 0.34925)
			(layers "F.Cu" "F.Mask" "F.Paste")
			(net "GND")
			(options
				(clearance outline)
				(anchor circle)
			)
			(primitives
				(gr_poly
					(pts
						(arc
							(start 1.49733 0.6985)
							(mid 1.09982 0.558768)
							(end 0.70231 0.6985)
						)
						(xy -2.921 0.6985) (xy -2.921 -0.6985) (xy 2.921 -0.6985) (xy 2.921 0.6985)
					)
					(width 0)
					(fill yes)
				)
			)
		)
		(pad "MP2" smd custom
			(at 2.00406 6.800596)
			(size 0.34925 0.34925)
			(layers "F.Cu" "F.Mask" "F.Paste")
			(net "GND")
			(options
				(clearance outline)
				(anchor circle)
			)
			(primitives
				(gr_poly
					(pts
						(arc
							(start 1.49733 -0.6985)
							(mid 1.09982 -0.558768)
							(end 0.70231 -0.6985)
						)
						(xy -2.921 -0.6985) (xy -2.921 0.6985) (xy 2.921 0.6985) (xy 2.921 -0.6985)
					)
					(width 0)
					(fill yes)
				)
			)
		)
		(zone
			(layers "F.Cu" "B.Cu" "In1.Cu" "In2.Cu" "In3.Cu" "In4.Cu" "In5.Cu" "In6.Cu"
				"In7.Cu" "In8.Cu" "In9.Cu" "In10.Cu" "In11.Cu" "In12.Cu"
			)
			(hatch none 0.5)
			(connect_pads
				(clearance 0)
			)
			(min_thickness 0.25)
			(keepout
				(tracks not_allowed)
				(vias allowed)
				(pads allowed)
				(copperpour not_allowed)
				(footprints allowed)
			)
			(placement
				(enabled no)
				(sheetname "")
			)
			(fill
				(thermal_gap 0.5)
				(thermal_bridge_width 0.5)
				(island_removal_mode 0)
			)
			(polygon
				(pts
					(arc
						(start 414.246568 -67.055746)
						(mid 412.849568 -67.055746)
						(end 414.246568 -67.055746)
					)
				)
			)
		)
		(zone
			(layers "F.Cu" "B.Cu" "In1.Cu" "In2.Cu" "In3.Cu" "In4.Cu" "In5.Cu" "In6.Cu"
				"In7.Cu" "In8.Cu" "In9.Cu" "In10.Cu" "In11.Cu" "In12.Cu"
			)
			(hatch none 0.5)
			(connect_pads
				(clearance 0)
			)
			(min_thickness 0.25)
			(keepout
				(tracks not_allowed)
				(vias allowed)
				(pads allowed)
				(copperpour not_allowed)
				(footprints allowed)
			)
			(placement
				(enabled no)
				(sheetname "")
			)
			(fill
				(thermal_gap 0.5)
				(thermal_bridge_width 0.5)
				(island_removal_mode 0)
			)
			(polygon
				(pts
					(arc
						(start 414.246568 -61.010546)
						(mid 412.849568 -61.010546)
						(end 414.246568 -61.010546)
					)
				)
			)
		)
	)
)
